# BASEBOARD_FAB2 (Tioga Pass) — schematic netlist excerpt (pin names and nets, part order shuffled) for the footprints in the layout excerpt that follows; sources: Cadence DE-HDL packaged netlist, KiCad conversion of Wiwynn_Tioga_Pass_MB.brd

C7A37  CAP_A  1.0UF 6.3V 10% X6S  pkg 0402V  page 218 : A = VR_PVDDQ_DEF_VDD ; B = GND
R8E25  RES  0.0 5% CHIP  pkg 0402  page 240 : A = P3V3_STBY ; B = VSENSE_P3V3_STBY
R1D52  RES  68.1K 1% EMPTY  pkg 0402  page 209 : A = VR_PVCCIN_CPU1_PH5_OCSET ; B = GND

(kicad_pcb
	(version 20260206)
	(generator "pcbnew")
	(generator_version "10.0")
	(general
		(thickness 1.6)
		(legacy_teardrops no)
	)
	(paper "A4")
	(title_block
		(title "Wiwynn_Tioga_Pass_MB.brd")
		(comment 1 "Tioga Pass / footprints 1825-1827 of 4770")
	)
	(layers
		(0 "F.Cu" signal "TOP")
		(4 "In1.Cu" signal "L2GND")
		(6 "In2.Cu" signal "L3")
		(8 "In3.Cu" signal "L4GND")
		(10 "In4.Cu" signal "L5")
		(12 "In5.Cu" signal "L6GND")
		(14 "In6.Cu" signal "L7VCC")
		(16 "In7.Cu" signal "L8VCC")
		(18 "In8.Cu" signal "L9GND")
		(20 "In9.Cu" signal "L10")
		(22 "In10.Cu" signal "L11GND")
		(24 "In11.Cu" signal "L12")
		(26 "In12.Cu" signal "L13GND")
		(2 "B.Cu" signal "BOTTOM")
		(9 "F.Adhes" user "F.Adhesive")
		(11 "B.Adhes" user "B.Adhesive")
		(13 "F.Paste" user "Package Geometry/Pastemask Top")
		(15 "B.Paste" user "Package Geometry/Pastemask Bottom")
		(5 "F.SilkS" user "Ref Des/Silkscreen Top")
		(7 "B.SilkS" user "Ref Des/Silkscreen Bottom")
		(1 "F.Mask" user "Board Geometry/Soldermask Top")
		(3 "B.Mask" user "Board Geometry/Soldermask Bottom")
		(17 "Dwgs.User" user "User.Drawings")
		(19 "Cmts.User" user "User.Comments")
		(21 "Eco1.User" user "User.Eco1")
		(23 "Eco2.User" user "User.Eco2")
		(25 "Edge.Cuts" user "Board Geometry/Outline")
		(27 "Margin" user)
		(31 "F.CrtYd" user "Package Geometry/Place Bound Top")
		(29 "B.CrtYd" user "Package Geometry/Place Bound Bottom")
		(35 "F.Fab" user "Ref Des/Assembly Top")
		(33 "B.Fab" user "Ref Des/Assembly Bottom")
	)
	(footprint ""
		(layer "F.Cu")
		(at 465.593938 -26.557224 90)
		(property "Reference" "R8E25"
			(at 0 0 90)
			(layer "F.SilkS")
			(hide yes)
			(effects
				(font
					(size 1.27 1.27)
				)
			)
		)
		(property "Value" ""
			(at 0 0 90)
			(layer "F.Fab")
			(effects
				(font
					(size 1.27 1.27)
				)
			)
		)
		(duplicate_pad_numbers_are_jumpers no)
		(fp_rect
			(start -0.2794 -0.1016)
			(end 0.2794 0.9906)
			(stroke
				(width 0)
				(type default)
			)
			(fill no)
			(layer "F.CrtYd")
		)
		(fp_line
			(start 0.2794 -0.1016)
			(end -0.2794 -0.1016)
			(stroke
				(width 0.1)
				(type default)
			)
			(layer "F.Fab")
		)
		(fp_line
			(start -0.2794 -0.1016)
			(end -0.2794 0.9906)
			(stroke
				(width 0.1)
				(type default)
			)
			(layer "F.Fab")
		)
		(fp_line
			(start 0.2794 0.9906)
			(end 0.2794 -0.1016)
			(stroke
				(width 0.1)
				(type default)
			)
			(layer "F.Fab")
		)
		(fp_line
			(start -0.2794 0.9906)
			(end 0.2794 0.9906)
			(stroke
				(width 0.1)
				(type default)
			)
			(layer "F.Fab")
		)
		(pad "1" smd rect
			(at 0 0 90)
			(size 0.508 0.508)
			(layers "F.Cu" "F.Mask" "F.Paste")
			(net "P3V3_STBY")
		)
		(pad "2" smd rect
			(at 0 0.889 90)
			(size 0.508 0.508)
			(layers "F.Cu" "F.Mask" "F.Paste")
			(net "VSENSE_P3V3_STBY")
		)
		(zone
			(layer "F.Cu")
			(hatch none 0.5)
			(connect_pads
				(clearance 0)
			)
			(min_thickness 0.25)
			(keepout
				(tracks not_allowed)
				(vias allowed)
				(pads allowed)
				(copperpour not_allowed)
				(footprints allowed)
			)
			(placement
				(enabled no)
				(sheetname "")
			)
			(fill
				(thermal_gap 0.5)
				(thermal_bridge_width 0.5)
				(island_removal_mode 0)
			)
			(polygon
				(pts
					(xy 465.847938 -26.303224) (xy 466.228938 -26.303224) (xy 466.228938 -26.811224) (xy 465.847938 -26.811224)
				)
			)
		)
		(zone
			(layer "F.Cu")
			(hatch none 0.5)
			(connect_pads
				(clearance 0)
			)
			(min_thickness 0.25)
			(keepout
				(tracks allowed)
				(vias not_allowed)
				(pads allowed)
				(copperpour not_allowed)
				(footprints allowed)
			)
			(placement
				(enabled no)
				(sheetname "")
			)
			(fill
				(thermal_gap 0.5)
				(thermal_bridge_width 0.5)
				(island_removal_mode 0)
			)
			(polygon
				(pts
					(xy 465.847938 -26.303224) (xy 466.228938 -26.303224) (xy 466.228938 -26.811224) (xy 465.847938 -26.811224)
				)
			)
		)
	)
	(footprint ""
		(layer "F.Cu")
		(at 354.36048 -135.742934)
		(property "Reference" "C7A37"
			(at 0 0 0)
			(layer "F.SilkS")
			(hide yes)
			(effects
				(font
					(size 1.27 1.27)
				)
			)
		)
		(property "Value" ""
			(at 0 0 0)
			(layer "F.Fab")
			(effects
				(font
					(size 1.27 1.27)
				)
			)
		)
		(duplicate_pad_numbers_are_jumpers no)
		(fp_poly
			(pts
				(xy 0.3048 -0.1016) (xy 0.3048 0.9906) (xy -0.3048 0.9906) (xy -0.3048 -0.1016)
			)
			(stroke
				(width 0)
				(type default)
			)
			(fill no)
			(layer "F.CrtYd")
		)
		(fp_line
			(start -0.3048 -0.1016)
			(end -0.3048 0.9906)
			(stroke
				(width 0.1)
				(type default)
			)
			(layer "F.Fab")
		)
		(fp_line
			(start -0.3048 0.9906)
			(end 0.3048 0.9906)
			(stroke
				(width 0.1)
				(type default)
			)
			(layer "F.Fab")
		)
		(fp_line
			(start 0.3048 -0.1016)
			(end -0.3048 -0.1016)
			(stroke
				(width 0.1)
				(type default)
			)
			(layer "F.Fab")
		)
		(fp_line
			(start 0.3048 0.9906)
			(end 0.3048 -0.1016)
			(stroke
				(width 0.1)
				(type default)
			)
			(layer "F.Fab")
		)
		(pad "1" smd rect
			(at 0 0)
			(size 0.508 0.508)
			(layers "F.Cu" "F.Mask" "F.Paste")
			(net "VR_PVDDQ_DEF_VDD")
		)
		(pad "2" smd rect
			(at 0 0.889)
			(size 0.508 0.508)
			(layers "F.Cu" "F.Mask" "F.Paste")
			(net "GND")
		)
		(zone
			(layer "F.Cu")
			(hatch none 0.5)
			(connect_pads
				(clearance 0)
			)
			(min_thickness 0.25)
			(keepout
				(tracks allowed)
				(vias not_allowed)
				(pads allowed)
				(copperpour not_allowed)
				(footprints allowed)
			)
			(placement
				(enabled no)
				(sheetname "")
			)
			(fill
				(thermal_gap 0.5)
				(thermal_bridge_width 0.5)
				(island_removal_mode 0)
			)
			(polygon
				(pts
					(xy 354.10648 -135.488934) (xy 354.61448 -135.488934) (xy 354.61448 -135.107934) (xy 354.10648 -135.107934)
				)
			)
		)
		(zone
			(layer "F.Cu")
			(hatch none 0.5)
			(connect_pads
				(clearance 0)
			)
			(min_thickness 0.25)
			(keepout
				(tracks not_allowed)
				(vias allowed)
				(pads allowed)
				(copperpour not_allowed)
				(footprints allowed)
			)
			(placement
				(enabled no)
				(sheetname "")
			)
			(fill
				(thermal_gap 0.5)
				(thermal_bridge_width 0.5)
				(island_removal_mode 0)
			)
			(polygon
				(pts
					(xy 354.10648 -135.107934) (xy 354.61448 -135.107934) (xy 354.61448 -135.488934) (xy 354.10648 -135.488934)
				)
			)
		)
	)
	(footprint ""
		(layer "F.Cu")
		(at 28.794964 -88.540844 -90)
		(property "Reference" "R1D52"
			(at 0 0 270)
			(layer "F.SilkS")
			(hide yes)
			(effects
				(font
					(size 1.27 1.27)
				)
			)
		)
		(property "Value" ""
			(at 0 0 270)
			(layer "F.Fab")
			(effects
				(font
					(size 1.27 1.27)
				)
			)
		)
		(duplicate_pad_numbers_are_jumpers no)
		(fp_poly
			(pts
				(xy -0.2794 -0.1016) (xy 0.2794 -0.1016) (xy 0.2794 0.9906) (xy -0.2794 0.9906)
			)
			(stroke
				(width 0)
				(type default)
			)
			(fill no)
			(layer "F.CrtYd")
		)
		(fp_line
			(start -0.2794 0.9906)
			(end 0.2794 0.9906)
			(stroke
				(width 0.1)
				(type default)
			)
			(layer "F.Fab")
		)
		(fp_line
			(start 0.2794 0.9906)
			(end 0.2794 -0.1016)
			(stroke
				(width 0.1)
				(type default)
			)
			(layer "F.Fab")
		)
		(fp_line
			(start -0.2794 -0.1016)
			(end -0.2794 0.9906)
			(stroke
				(width 0.1)
				(type default)
			)
			(layer "F.Fab")
		)
		(fp_line
			(start 0.2794 -0.1016)
			(end -0.2794 -0.1016)
			(stroke
				(width 0.1)
				(type default)
			)
			(layer "F.Fab")
		)
		(pad "1" smd rect
			(at 0 0 270)
			(size 0.508 0.508)
			(layers "F.Cu" "F.Mask" "F.Paste")
			(net "VR_PVCCIN_CPU1_PH5_OCSET")
		)
		(pad "2" smd rect
			(at 0 0.889 270)
			(size 0.508 0.508)
			(layers "F.Cu" "F.Mask" "F.Paste")
			(net "GND")
		)
		(zone
			(layer "F.Cu")
			(hatch none 0.5)
			(connect_pads
				(clearance 0)
			)
			(min_thickness 0.25)
			(keepout
				(tracks not_allowed)
				(vias allowed)
				(pads allowed)
				(copperpour not_allowed)
				(footprints allowed)
			)
			(placement
				(enabled no)
				(sheetname "")
			)
			(fill
				(thermal_gap 0.5)
				(thermal_bridge_width 0.5)
				(island_removal_mode 0)
			)
			(polygon
				(pts
					(xy 28.159964 -88.794844) (xy 28.159964 -88.286844) (xy 28.540964 -88.286844) (xy 28.540964 -88.794844)
				)
			)
		)
		(zone
			(layer "F.Cu")
			(hatch none 0.5)
			(connect_pads
				(clearance 0)
			)
			(min_thickness 0.25)
			(keepout
				(tracks allowed)
				(vias not_allowed)
				(pads allowed)
				(copperpour not_allowed)
				(footprints allowed)
			)
			(placement
				(enabled no)
				(sheetname "")
			)
			(fill
				(thermal_gap 0.5)
				(thermal_bridge_width 0.5)
				(island_removal_mode 0)
			)
			(polygon
				(pts
					(xy 28.540964 -88.794844) (xy 28.540964 -88.286844) (xy 28.159964 -88.286844) (xy 28.159964 -88.794844)
				)
			)
		)
	)
)
